(kicad_pcb
	(version 20260206)
	(generator "pcbnew")
	(generator_version "10.0")
	(general
		(thickness 1.6)
		(legacy_teardrops no)
	)
	(paper "A4")
	(title_block
		(title "Wiwynn_Tioga_Pass_MB.brd")
		(comment 1 "Tioga Pass / footprints 188-189 of 4770")
	)
	(layers
		(0 "F.Cu" signal "TOP")
		(4 "In1.Cu" signal "L2GND")
		(6 "In2.Cu" signal "L3")
		(8 "In3.Cu" signal "L4GND")
		(10 "In4.Cu" signal "L5")
		(12 "In5.Cu" signal "L6GND")
		(14 "In6.Cu" signal "L7VCC")
		(16 "In7.Cu" signal "L8VCC")
		(18 "In8.Cu" signal "L9GND")
		(20 "In9.Cu" signal "L10")
		(22 "In10.Cu" signal "L11GND")
		(24 "In11.Cu" signal "L12")
		(26 "In12.Cu" signal "L13GND")
		(2 "B.Cu" signal "BOTTOM")
		(9 "F.Adhes" user "F.Adhesive")
		(11 "B.Adhes" user "B.Adhesive")
		(13 "F.Paste" user "Package Geometry/Pastemask Top")
		(15 "B.Paste" user "Package Geometry/Pastemask Bottom")
		(5 "F.SilkS" user "Ref Des/Silkscreen Top")
		(7 "B.SilkS" user "Ref Des/Silkscreen Bottom")
		(1 "F.Mask" user "Board Geometry/Soldermask Top")
		(3 "B.Mask" user "Board Geometry/Soldermask Bottom")
		(17 "Dwgs.User" user "User.Drawings")
		(19 "Cmts.User" user "User.Comments")
		(21 "Eco1.User" user "User.Eco1")
		(23 "Eco2.User" user "User.Eco2")
		(25 "Edge.Cuts" user "Board Geometry/Outline")
		(27 "Margin" user)
		(31 "F.CrtYd" user "Package Geometry/Place Bound Top")
		(29 "B.CrtYd" user "Package Geometry/Place Bound Bottom")
		(35 "F.Fab" user "Ref Des/Assembly Top")
		(33 "B.Fab" user "Ref Des/Assembly Bottom")
	)
	(footprint ""
		(layer "F.Cu")
		(at 181.9656 -135.9662 180)
		(property "Reference" "C4A20"
			(at 0 0 180)
			(layer "F.SilkS")
			(hide yes)
			(effects
				(font
					(size 1.27 1.27)
				)
			)
		)
		(property "Value" ""
			(at 0 0 180)
			(layer "F.Fab")
			(effects
				(font
					(size 1.27 1.27)
				)
			)
		)
		(duplicate_pad_numbers_are_jumpers no)
		(fp_poly
			(pts
				(xy 0.3048 -0.1016) (xy 0.3048 0.9906) (xy -0.3048 0.9906) (xy -0.3048 -0.1016)
			)
			(stroke
				(width 0)
				(type default)
			)
			(fill no)
			(layer "F.CrtYd")
		)
		(fp_line
			(start 0.3048 0.9906)
			(end 0.3048 -0.1016)
			(stroke
				(width 0.1)
				(type default)
			)
			(layer "F.Fab")
		)
		(fp_line
			(start 0.3048 -0.1016)
			(end -0.3048 -0.1016)
			(stroke
				(width 0.1)
				(type default)
			)
			(layer "F.Fab")
		)
		(fp_line
			(start -0.3048 0.9906)
			(end 0.3048 0.9906)
			(stroke
				(width 0.1)
				(type default)
			)
			(layer "F.Fab")
		)
		(fp_line
			(start -0.3048 -0.1016)
			(end -0.3048 0.9906)
			(stroke
				(width 0.1)
				(type default)
			)
			(layer "F.Fab")
		)
		(pad "1" smd rect
			(at 0 0 180)
			(size 0.508 0.508)
			(layers "F.Cu" "F.Mask" "F.Paste")
			(net "VR_FET_SW_P12V_STBY_PVPP_KLM")
		)
		(pad "2" smd rect
			(at 0 0.889 180)
			(size 0.508 0.508)
			(layers "F.Cu" "F.Mask" "F.Paste")
			(net "GND")
		)
		(zone
			(layer "F.Cu")
			(hatch none 0.5)
			(connect_pads
				(clearance 0)
			)
			(min_thickness 0.25)
			(keepout
				(tracks not_allowed)
				(vias allowed)
				(pads allowed)
				(copperpour not_allowed)
				(footprints allowed)
			)
			(placement
				(enabled no)
				(sheetname "")
			)
			(fill
				(thermal_gap 0.5)
				(thermal_bridge_width 0.5)
				(island_removal_mode 0)
			)
			(polygon
				(pts
					(xy 182.2196 -136.6012) (xy 181.7116 -136.6012) (xy 181.7116 -136.2202) (xy 182.2196 -136.2202)
				)
			)
		)
		(zone
			(layer "F.Cu")
			(hatch none 0.5)
			(connect_pads
				(clearance 0)
			)
			(min_thickness 0.25)
			(keepout
				(tracks allowed)
				(vias not_allowed)
				(pads allowed)
				(copperpour not_allowed)
				(footprints allowed)
			)
			(placement
				(enabled no)
				(sheetname "")
			)
			(fill
				(thermal_gap 0.5)
				(thermal_bridge_width 0.5)
				(island_removal_mode 0)
			)
			(polygon
				(pts
					(xy 182.2196 -136.2202) (xy 181.7116 -136.2202) (xy 181.7116 -136.6012) (xy 182.2196 -136.6012)
				)
			)
		)
	)
	(footprint ""
		(layer "F.Cu")
		(at 497.05006 -57.079896 90)
		(property "Reference" "J30W1"
			(at 0 0 90)
			(layer "F.SilkS")
			(hide yes)
			(effects
				(font
					(size 1.27 1.27)
				)
			)
		)
		(property "Value" "*"
			(at 6.604 -3.1623 90)
			(unlocked yes)
			(layer "F.Fab")
			(hide yes)
			(effects
				(font
					(size 1.27 1.016)
					(thickness 0.1524)
				)
			)
		)
		(property "Device Type" "SKT-USB32-8-GP_SOCKET-G4-SKT-UA"
			(at 6.604 -4.6863 90)
			(unlocked yes)
			(layer "F.Fab")
			(hide yes)
			(effects
				(font
					(size 1.27 1.016)
					(thickness 0.1524)
				)
			)
		)
		(duplicate_pad_numbers_are_jumpers no)
		(fp_line
			(start 3.665474 -2.71526)
			(end 4.275074 -2.71526)
			(stroke
				(width 0.3048)
				(type default)
			)
			(layer "F.SilkS")
		)
		(fp_line
			(start 0.758698 -2.71526)
			(end 1.241298 -2.71526)
			(stroke
				(width 0.3048)
				(type default)
			)
			(layer "F.SilkS")
		)
		(fp_line
			(start -1.241298 -2.71526)
			(end -0.758698 -2.71526)
			(stroke
				(width 0.3048)
				(type default)
			)
			(layer "F.SilkS")
		)
		(fp_line
			(start -4.275074 -2.71526)
			(end -3.665474 -2.71526)
			(stroke
				(width 0.3048)
				(type default)
			)
			(layer "F.SilkS")
		)
		(fp_line
			(start 5.3594 -2.6162)
			(end -5.3594 -2.6162)
			(stroke
				(width 0.1524)
				(type default)
			)
			(layer "F.SilkS")
		)
		(fp_line
			(start -5.3594 -2.6162)
			(end -5.3594 7.366)
			(stroke
				(width 0.1524)
				(type default)
			)
			(layer "F.SilkS")
		)
		(fp_line
			(start 5.240274 -1.75006)
			(end 5.240274 -0.60706)
			(stroke
				(width 0.3048)
				(type default)
			)
			(layer "F.SilkS")
		)
		(fp_line
			(start -5.240274 -0.60706)
			(end -5.240274 -1.75006)
			(stroke
				(width 0.3048)
				(type default)
			)
			(layer "F.SilkS")
		)
		(fp_line
			(start 5.465318 2.716022)
			(end 5.465318 3.884422)
			(stroke
				(width 0.3048)
				(type default)
			)
			(layer "F.SilkS")
		)
		(fp_line
			(start -3.534918 2.716022)
			(end -3.534918 3.884422)
			(stroke
				(width 0.3048)
				(type default)
			)
			(layer "F.SilkS")
		)
		(fp_line
			(start 3.534918 3.884422)
			(end 3.534918 2.716022)
			(stroke
				(width 0.3048)
				(type default)
			)
			(layer "F.SilkS")
		)
		(fp_line
			(start -5.465318 3.884422)
			(end -5.465318 2.716022)
			(stroke
				(width 0.3048)
				(type default)
			)
			(layer "F.SilkS")
		)
		(fp_line
			(start 5.3594 7.366)
			(end 5.3594 -2.6162)
			(stroke
				(width 0.1524)
				(type default)
			)
			(layer "F.SilkS")
		)
		(fp_line
			(start -5.3594 7.366)
			(end 5.3594 7.366)
			(stroke
				(width 0.1524)
				(type default)
			)
			(layer "F.SilkS")
		)
		(fp_arc
			(start 4.275074 -2.71526)
			(mid 4.957573 -2.432559)
			(end 5.240274 -1.75006)
			(stroke
				(width 0.3048)
				(type default)
			)
			(layer "F.SilkS")
		)
		(fp_arc
			(start 1.241298 -2.71526)
			(mid 1.948816 -2.35599)
			(end 2.076196 -1.572768)
			(stroke
				(width 0.3048)
				(type default)
			)
			(layer "F.SilkS")
		)
		(fp_arc
			(start -0.758698 -2.71526)
			(mid -0.320687 -2.597938)
			(end 0 -2.277364)
			(stroke
				(width 0.3048)
				(type default)
			)
			(layer "F.SilkS")
		)
		(fp_arc
			(start -3.665474 -2.71526)
			(mid -3.006095 -2.455016)
			(end -2.702306 -1.814576)
			(stroke
				(width 0.3048)
				(type default)
			)
			(layer "F.SilkS")
		)
		(fp_arc
			(start 0 -2.277364)
			(mid 0.32071 -2.597898)
			(end 0.758698 -2.71526)
			(stroke
				(width 0.3048)
				(type default)
			)
			(layer "F.SilkS")
		)
		(fp_arc
			(start -5.240274 -1.75006)
			(mid -4.957573 -2.432559)
			(end -4.275074 -2.71526)
			(stroke
				(width 0.3048)
				(type default)
			)
			(layer "F.SilkS")
		)
		(fp_arc
			(start 2.70637 -1.642618)
			(mid 2.946059 -2.393384)
			(end 3.665474 -2.71526)
			(stroke
				(width 0.3048)
				(type default)
			)
			(layer "F.SilkS")
		)
		(fp_arc
			(start -2.078736 -1.580896)
			(mid -1.946295 -2.359421)
			(end -1.241298 -2.71526)
			(stroke
				(width 0.3048)
				(type default)
			)
			(layer "F.SilkS")
		)
		(fp_arc
			(start 5.240274 -0.60706)
			(mid 4.78892 0.209992)
			(end 3.85699 0.26289)
			(stroke
				(width 0.3048)
				(type default)
			)
			(layer "F.SilkS")
		)
		(fp_arc
			(start -4.015232 0.32258)
			(mid -4.858568 0.161889)
			(end -5.240274 -0.60706)
			(stroke
				(width 0.3048)
				(type default)
			)
			(layer "F.SilkS")
		)
		(fp_arc
			(start 3.756914 0.589534)
			(mid 4.197376 1.413733)
			(end 3.474974 2.0066)
			(stroke
				(width 0.3048)
				(type default)
			)
			(layer "F.SilkS")
		)
		(fp_arc
			(start -2.8829 1.708404)
			(mid -3.143508 1.927851)
			(end -3.474974 2.0066)
			(stroke
				(width 0.3048)
				(type default)
			)
			(layer "F.SilkS")
		)
		(fp_arc
			(start 3.474974 2.0066)
			(mid 3.18054 1.945172)
			(end 2.935224 1.771142)
			(stroke
				(width 0.3048)
				(type default)
			)
			(layer "F.SilkS")
		)
		(fp_arc
			(start -3.474974 2.0066)
			(mid -4.181898 1.476973)
			(end -3.87223 0.649732)
			(stroke
				(width 0.3048)
				(type default)
			)
			(layer "F.SilkS")
		)
		(fp_arc
			(start 3.534918 2.716022)
			(mid 4.500118 1.750822)
			(end 5.465318 2.716022)
			(stroke
				(width 0.3048)
				(type default)
			)
			(layer "F.SilkS")
		)
		(fp_arc
			(start -5.465318 2.716022)
			(mid -4.500118 1.750822)
			(end -3.534918 2.716022)
			(stroke
				(width 0.3048)
				(type default)
			)
			(layer "F.SilkS")
		)
		(fp_arc
			(start 5.465318 3.884422)
			(mid 4.500118 4.849622)
			(end 3.534918 3.884422)
			(stroke
				(width 0.3048)
				(type default)
			)
			(layer "F.SilkS")
		)
		(fp_arc
			(start -3.534918 3.884422)
			(mid -4.500118 4.849622)
			(end -5.465318 3.884422)
			(stroke
				(width 0.3048)
				(type default)
			)
			(layer "F.SilkS")
		)
		(fp_rect
			(start -4.6228 7.112)
			(end 4.6228 -1.8288)
			(stroke
				(width 0)
				(type default)
			)
			(fill no)
			(layer "F.CrtYd")
		)
		(fp_poly
			(pts
				(xy -5.6134 7.62) (xy -5.6134 -2.8702) (xy 5.6134 -2.8702) (xy 5.6134 -0.00635) (xy 4.6228 -0.00635)
				(xy 4.6228 -1.8288) (xy -4.6228 -1.8288) (xy -4.6228 7.112) (xy 4.6228 7.112) (xy 4.6228 0.00635)
				(xy 5.6134 0.00635) (xy 5.6134 7.62)
			)
			(stroke
				(width 0)
				(type default)
			)
			(fill no)
			(layer "F.CrtYd")
		)
		(fp_rect
			(start -5.6134 7.62)
			(end 5.6134 -2.8702)
			(stroke
				(width 0)
				(type default)
			)
			(fill no)
			(layer "F.Fab")
		)
		(pad "" np_thru_hole circle
			(at -3.350006 0 90)
			(size 0.254 0.254)
			(drill 0.762)
			(layers "*.Cu" "*.Mask")
			(clearance 0.6096)
			(thermal_gap 0.6096)
		)
		(pad "" np_thru_hole circle
			(at 3.150108 0 90)
			(size 0.254 0.254)
			(drill 0.6604)
			(layers "*.Cu" "*.Mask")
			(clearance 0.5588)
			(thermal_gap 0.5588)
		)
		(pad "A1" smd rect
			(at -2.750058 -0.8001 90)
			(size 0.3048 0.8128)
			(layers "F.Cu" "F.Mask" "F.Paste")
			(net "GND")
		)
		(pad "A2" smd rect
			(at -2.249932 -0.8001 90)
			(size 0.3048 0.8128)
			(layers "F.Cu" "F.Mask" "F.Paste")
			(net "USB3_P01_FB_TXP")
		)
		(pad "A3" smd rect
			(at -1.75006 -0.8001 90)
			(size 0.3048 0.8128)
			(layers "F.Cu" "F.Mask" "F.Paste")
			(net "USB3_P01_FB_TXN")
		)
		(pad "A4" smd rect
			(at -1.249934 -0.7493 90)
			(size 0.3048 0.7112)
			(layers "F.Cu" "F.Mask" "F.Paste")
			(net "P5V_STBY_USBC")
		)
		(pad "A5" smd rect
			(at -0.750062 -0.7493 90)
			(size 0.3048 0.7112)
			(layers "F.Cu" "F.Mask" "F.Paste")
			(net "Net_6503")
		)
		(pad "A6" smd rect
			(at -0.249936 -0.8001 90)
			(size 0.3048 0.8128)
			(layers "F.Cu" "F.Mask" "F.Paste")
			(net "Net_6499")
		)
		(pad "A7" smd rect
			(at 0.249936 -0.8001 90)
			(size 0.3048 0.8128)
			(layers "F.Cu" "F.Mask" "F.Paste")
			(net "Net_6501")
		)
		(pad "A8" smd rect
			(at 0.750062 -0.7493 90)
			(size 0.3048 0.7112)
			(layers "F.Cu" "F.Mask" "F.Paste")
			(net "Net_6495")
		)
		(pad "A9" smd rect
			(at 1.249934 -0.7493 90)
			(size 0.3048 0.7112)
			(layers "F.Cu" "F.Mask" "F.Paste")
			(net "P5V_STBY_USBC")
		)
		(pad "A10" smd rect
			(at 1.75006 -0.8001 90)
			(size 0.3048 0.8128)
			(layers "F.Cu" "F.Mask" "F.Paste")
			(net "Net_6493")
		)
		(pad "A11" smd rect
			(at 2.249932 -0.8001 90)
			(size 0.3048 0.8128)
			(layers "F.Cu" "F.Mask" "F.Paste")
			(net "Net_6492")
		)
		(pad "A12" smd custom
			(at 2.750058 -0.8001 90)
			(size 0.0762 0.0762)
			(layers "F.Cu" "F.Mask" "F.Paste")
			(net "GND")
			(options
				(clearance outline)
				(anchor circle)
			)
			(primitives
				(gr_poly
					(pts
						(xy -0.1524 0.4064) (xy -0.1524 -0.4064) (xy 0.1524 -0.4064)
						(arc
							(start 0.1524 0.284988)
							(mid 0.063554 0.338103)
							(end -0.014224 0.4064)
						)
					)
					(width 0)
					(fill yes)
				)
			)
		)
		(pad "B1" smd rect
			(at 2.724658 0.899922 90)
			(size 0.254 0.8128)
			(layers "F.Cu" "F.Mask" "F.Paste")
			(net "GND")
		)
		(pad "B2" smd rect
			(at 2.249932 0.899922 90)
			(size 0.3048 0.8128)
			(layers "F.Cu" "F.Mask" "F.Paste")
			(net "Net_380")
		)
		(pad "B3" smd rect
			(at 1.75006 0.899922 90)
			(size 0.3048 0.8128)
			(layers "F.Cu" "F.Mask" "F.Paste")
			(net "Net_381")
		)
		(pad "B4" smd rect
			(at 1.249934 0.899922 90)
			(size 0.3048 0.8128)
			(layers "F.Cu" "F.Mask" "F.Paste")
			(net "P5V_STBY_USBC")
		)
		(pad "B5" smd rect
			(at 0.750062 0.899922 90)
			(size 0.3048 0.8128)
			(layers "F.Cu" "F.Mask" "F.Paste")
			(net "Net_6502")
		)
		(pad "B6" smd rect
			(at 0.249936 0.899922 90)
			(size 0.3048 0.8128)
			(layers "F.Cu" "F.Mask" "F.Paste")
			(net "Net_6498")
		)
		(pad "B7" smd rect
			(at -0.249936 0.899922 90)
			(size 0.3048 0.8128)
			(layers "F.Cu" "F.Mask" "F.Paste")
			(net "Net_6500")
		)
		(pad "B8" smd rect
			(at -0.750062 0.899922 90)
			(size 0.3048 0.8128)
			(layers "F.Cu" "F.Mask" "F.Paste")
			(net "Net_6494")
		)
		(pad "B9" smd rect
			(at -1.249934 0.899922 90)
			(size 0.3048 0.8128)
			(layers "F.Cu" "F.Mask" "F.Paste")
			(net "P5V_STBY_USBC")
		)
		(pad "B10" smd rect
			(at -1.75006 0.899922 90)
			(size 0.3048 0.8128)
			(layers "F.Cu" "F.Mask" "F.Paste")
			(net "USB3_P01_FB_RXN")
		)
		(pad "B11" smd rect
			(at -2.249932 0.899922 90)
			(size 0.3048 0.8128)
			(layers "F.Cu" "F.Mask" "F.Paste")
			(net "USB3_P01_FB_RXP")
		)
		(pad "B12" smd rect
			(at -2.724658 0.899922 90)
			(size 0.254 0.8128)
			(layers "F.Cu" "F.Mask" "F.Paste")
			(net "GND")
		)
		(pad "PTH1" thru_hole custom
			(at -4.275074 -1.75006 90)
			(size 0.457329 0.457329)
			(drill 0.0254)
			(layers "*.Cu" "*.Mask")
			(remove_unused_layers no)
			(net "GND")
			(clearance 0.254)
			(thermal_gap 0.254)
			(options
				(clearance outline)
				(anchor circle)
			)
			(primitives
				(gr_poly
					(pts
						(arc
							(start 0.045974 1.070102)
							(mid -0.585696 1.112558)
							(end -0.9144 0.5715)
						)
						(arc
							(start -0.9144 -0.5715)
							(mid -0.735852 -1.002552)
							(end -0.3048 -1.1811)
						)
						(arc
							(start 0.3048 -1.1811)
							(mid 0.9144 -0.5715)
							(end 0.3048 0.0381)
						)
						(arc
							(start 0.3048 0.5715)
							(mid 0.301608 0.633547)
							(end 0.2921 0.694944)
						)
						(arc
							(start 0.2921 0.694944)
							(mid 0.1316 0.857963)
							(end 0.045974 1.070102)
						)
					)
					(width 0)
					(fill yes)
				)
			)
		)
		(pad "PTH2" thru_hole custom
			(at 4.275074 -1.75006 90)
			(size 0.457329 0.457329)
			(drill 0.0254)
			(layers "*.Cu" "*.Mask")
			(remove_unused_layers no)
			(net "GND")
			(clearance 0.254)
			(thermal_gap 0.254)
			(options
				(clearance outline)
				(anchor circle)
			)
			(primitives
				(gr_poly
					(pts
						(arc
							(start 0.9144 0.5715)
							(mid 0.3048 1.1811)
							(end -0.3048 0.5715)
						)
						(arc
							(start -0.3048 0.0381)
							(mid -0.9144 -0.5715)
							(end -0.3048 -1.1811)
						)
						(arc
							(start 0.3048 -1.1811)
							(mid 0.735852 -1.002552)
							(end 0.9144 -0.5715)
						)
					)
					(width 0)
					(fill yes)
				)
			)
		)
		(pad "PTH3" thru_hole oval
			(at -0.999998 -1.75006 90)
			(size 1.524 1.0414)
			(drill oval 0.8128 0.508
				(offset 0 -0.0889)
			)
			(layers "*.Cu" "*.Mask")
			(remove_unused_layers no)
			(net "GND")
			(clearance 0.1524)
			(thermal_gap 0.1524)
		)
		(pad "PTH4" thru_hole oval
			(at 0.999998 -1.75006 90)
			(size 1.524 1.0414)
			(drill oval 0.8128 0.508
				(offset 0 -0.0889)
			)
			(layers "*.Cu" "*.Mask")
			(remove_unused_layers no)
			(net "GND")
			(clearance 0.1524)
			(thermal_gap 0.1524)
		)
		(pad "PTH5" thru_hole circle
			(at -3.474974 1.27 90)
			(size 0.762 0.762)
			(drill 0.4572)
			(layers "*.Cu" "*.Mask")
			(remove_unused_layers no)
			(net "GND")
			(clearance 0.2032)
			(thermal_gap 0.2032)
		)
		(pad "PTH6" thru_hole circle
			(at 3.474974 1.27 90)
			(size 0.762 0.762)
			(drill 0.4572)
			(layers "*.Cu" "*.Mask")
			(remove_unused_layers no)
			(net "GND")
			(clearance 0.2032)
			(thermal_gap 0.2032)
		)
		(pad "PTH7" thru_hole oval
			(at -4.500118 3.50012 90)
			(size 1.2192 2.3876)
			(drill oval 0.508 1.524
				(offset 0 -0.199898)
			)
			(layers "*.Cu" "*.Mask")
			(remove_unused_layers no)
			(net "GND")
			(clearance 0.1524)
			(thermal_gap 0.1524)
		)
		(pad "PTH8" thru_hole oval
			(at 4.500118 3.50012 90)
			(size 1.2192 2.3876)
			(drill oval 0.508 1.524
				(offset 0 -0.199898)
			)
			(layers "*.Cu" "*.Mask")
			(remove_unused_layers no)
			(net "GND")
			(clearance 0.1524)
			(thermal_gap 0.1524)
		)
		(zone
			(layers "F.Cu" "B.Cu" "In1.Cu" "In2.Cu" "In3.Cu" "In4.Cu" "In5.Cu" "In6.Cu"
				"In7.Cu" "In8.Cu" "In9.Cu" "In10.Cu" "In11.Cu" "In12.Cu"
			)
			(hatch none 0.5)
			(connect_pads
				(clearance 0)
			)
			(min_thickness 0.25)
			(keepout
				(tracks not_allowed)
				(vias allowed)
				(pads allowed)
				(copperpour not_allowed)
				(footprints allowed)
			)
			(placement
				(enabled no)
				(sheetname "")
			)
			(fill
				(thermal_gap 0.5)
				(thermal_bridge_width 0.5)
				(island_removal_mode 0)
			)
			(polygon
				(pts
					(arc
						(start 497.68506 -60.230004)
						(mid 496.41506 -60.230004)
						(end 497.68506 -60.230004)
					)
				)
			)
		)
		(zone
			(layers "F.Cu" "B.Cu" "In1.Cu" "In2.Cu" "In3.Cu" "In4.Cu" "In5.Cu" "In6.Cu"
				"In7.Cu" "In8.Cu" "In9.Cu" "In10.Cu" "In11.Cu" "In12.Cu"
			)
			(hatch none 0.5)
			(connect_pads
				(clearance 0)
			)
			(min_thickness 0.25)
			(keepout
				(tracks not_allowed)
				(vias allowed)
				(pads allowed)
				(copperpour not_allowed)
				(footprints allowed)
			)
			(placement
				(enabled no)
				(sheetname "")
			)
			(fill
				(thermal_gap 0.5)
				(thermal_bridge_width 0.5)
				(island_removal_mode 0)
			)
			(polygon
				(pts
					(arc
						(start 497.73586 -53.72989)
						(mid 496.36426 -53.72989)
						(end 497.73586 -53.72989)
					)
				)
			)
		)
	)
)
